(kicad_pcb
	(version 20260206)
	(generator "pcbnew")
	(generator_version "10.0")
	(general
		(thickness 1.6)
		(legacy_teardrops no)
	)
	(paper "A4")
	(title_block
		(title "v1-pdb — T6M_PDB_D_0927_0900.brd")
		(comment 1 "Open CloudServer (Microsoft) / footprints 267-270 of 321")
	)
	(layers
		(0 "F.Cu" signal "TOP")
		(4 "In1.Cu" signal "GND")
		(6 "In2.Cu" signal "IN1")
		(8 "In3.Cu" signal "VCC")
		(10 "In4.Cu" signal "VCC1")
		(12 "In5.Cu" signal "IN2")
		(14 "In6.Cu" signal "GND1")
		(2 "B.Cu" signal "BOTTOM")
		(9 "F.Adhes" user "F.Adhesive")
		(11 "B.Adhes" user "B.Adhesive")
		(13 "F.Paste" user "Package Geometry/Pastemask Top")
		(15 "B.Paste" user "Package Geometry/Pastemask Bottom")
		(5 "F.SilkS" user "Ref Des/Silkscreen Top")
		(7 "B.SilkS" user "Ref Des/Silkscreen Bottom")
		(1 "F.Mask" user "Board Geometry/Soldermask Top")
		(3 "B.Mask" user "Board Geometry/Soldermask Bottom")
		(17 "Dwgs.User" user "User.Drawings")
		(19 "Cmts.User" user "User.Comments")
		(21 "Eco1.User" user "User.Eco1")
		(23 "Eco2.User" user "User.Eco2")
		(25 "Edge.Cuts" user "Board Geometry/Outline")
		(27 "Margin" user)
		(31 "F.CrtYd" user "Package Geometry/Place Bound Top")
		(29 "B.CrtYd" user "Package Geometry/Place Bound Bottom")
		(35 "F.Fab" user "Ref Des/Assembly Top")
		(33 "B.Fab" user "Ref Des/Assembly Bottom")
	)
	(footprint ""
		(layer "F.Cu")
		(at 69.370956 -194.090544 -90)
		(property "Reference" "C29"
			(at 0.407162 -4.16433 90)
			(unlocked yes)
			(layer "F.SilkS")
			(effects
				(font
					(size 0.7874 0.5842)
					(thickness 0.1524)
				)
			)
		)
		(property "Value" ""
			(at 0 0 270)
			(layer "F.Fab")
			(effects
				(font
					(size 1.27 1.27)
				)
			)
		)
		(duplicate_pad_numbers_are_jumpers no)
		(fp_line
			(start -1.2954 0.5842)
			(end -1.2954 -0.5842)
			(stroke
				(width 0.1524)
				(type default)
			)
			(layer "F.SilkS")
		)
		(fp_line
			(start 1.2954 0.5842)
			(end -1.2954 0.5842)
			(stroke
				(width 0.1524)
				(type default)
			)
			(layer "F.SilkS")
		)
		(fp_line
			(start -1.2954 -0.5842)
			(end 1.2954 -0.5842)
			(stroke
				(width 0.1524)
				(type default)
			)
			(layer "F.SilkS")
		)
		(fp_line
			(start 0 -0.5842)
			(end 0 0.5842)
			(stroke
				(width 0.1524)
				(type default)
			)
			(layer "F.SilkS")
		)
		(fp_line
			(start 1.2954 -0.5842)
			(end 1.2954 0.5842)
			(stroke
				(width 0.1524)
				(type default)
			)
			(layer "F.SilkS")
		)
		(fp_poly
			(pts
				(xy 0.8636 -0.4572) (xy 0.8636 -0.3556) (xy 1.143 -0.3556) (xy 1.143 0.3556) (xy 0.8636 0.3556)
				(xy 0.8636 0.4572) (xy -0.8636 0.4572) (xy -0.8636 0.3556) (xy -1.143 0.3556) (xy -1.143 -0.3556)
				(xy -0.8636 -0.3556) (xy -0.8636 -0.4572)
			)
			(stroke
				(width 0)
				(type default)
			)
			(fill no)
			(layer "F.CrtYd")
		)
		(fp_line
			(start -0.884936 0.504952)
			(end -0.884936 -0.504952)
			(stroke
				(width 0.1)
				(type default)
			)
			(layer "F.Fab")
		)
		(fp_line
			(start 0.884936 0.504952)
			(end -0.884936 0.504952)
			(stroke
				(width 0.1)
				(type default)
			)
			(layer "F.Fab")
		)
		(fp_line
			(start -0.884936 -0.504952)
			(end 0.884936 -0.504952)
			(stroke
				(width 0.1)
				(type default)
			)
			(layer "F.Fab")
		)
		(fp_line
			(start 0.884936 -0.504952)
			(end 0.884936 0.504952)
			(stroke
				(width 0.1)
				(type default)
			)
			(layer "F.Fab")
		)
		(pad "1" smd rect
			(at 0.7366 0)
			(size 0.7112 0.8128)
			(layers "F.Cu" "F.Mask" "F.Paste")
			(net "P12V")
		)
		(pad "2" smd rect
			(at -0.7366 0)
			(size 0.7112 0.8128)
			(layers "F.Cu" "F.Mask" "F.Paste")
			(net "GND")
		)
	)
	(footprint ""
		(layer "F.Cu")
		(at 74.153522 -42.631106 90)
		(property "Reference" "C12"
			(at -1.11506 4.720336 90)
			(unlocked yes)
			(layer "F.SilkS")
			(effects
				(font
					(size 0.7874 0.5842)
					(thickness 0.1524)
				)
				(justify left)
			)
		)
		(property "Value" ""
			(at 0 0 90)
			(layer "F.Fab")
			(effects
				(font
					(size 1.27 1.27)
				)
			)
		)
		(duplicate_pad_numbers_are_jumpers no)
		(fp_line
			(start 0.7874 -0.4064)
			(end 0.7874 0.4064)
			(stroke
				(width 0.1524)
				(type default)
			)
			(layer "F.SilkS")
		)
		(fp_line
			(start -0.7874 -0.4064)
			(end 0.7874 -0.4064)
			(stroke
				(width 0.1524)
				(type default)
			)
			(layer "F.SilkS")
		)
		(fp_line
			(start 0 0.381)
			(end 0 -0.381)
			(stroke
				(width 0.1524)
				(type default)
			)
			(layer "F.SilkS")
		)
		(fp_line
			(start 0.7874 0.4064)
			(end -0.7874 0.4064)
			(stroke
				(width 0.1524)
				(type default)
			)
			(layer "F.SilkS")
		)
		(fp_line
			(start -0.7874 0.4064)
			(end -0.7874 -0.4064)
			(stroke
				(width 0.1524)
				(type default)
			)
			(layer "F.SilkS")
		)
		(fp_poly
			(pts
				(xy -0.5334 0.254) (xy -0.635 0.254) (xy -0.635 0.2286) (xy -0.635 -0.254) (xy -0.5334 -0.254) (xy -0.5334 -0.2794)
				(xy 0.5334 -0.2794) (xy 0.5334 -0.254) (xy 0.635 -0.254) (xy 0.635 0.254) (xy 0.5334 0.254) (xy 0.5334 0.2794)
				(xy -0.508 0.2794) (xy -0.5334 0.2794)
			)
			(stroke
				(width 0)
				(type default)
			)
			(fill no)
			(layer "F.CrtYd")
		)
		(pad "1" smd rect
			(at 0.40005 0 90)
			(size 0.4572 0.508)
			(layers "F.Cu" "F.Mask" "F.Paste")
			(net "P12V")
		)
		(pad "2" smd rect
			(at -0.40005 0 90)
			(size 0.4572 0.508)
			(layers "F.Cu" "F.Mask" "F.Paste")
			(net "GND")
		)
	)
	(footprint ""
		(layer "F.Cu")
		(at 69.774816 -442.84646 90)
		(property "Reference" "C77"
			(at -3.83667 0.064516 90)
			(unlocked yes)
			(layer "F.SilkS")
			(effects
				(font
					(size 0.7874 0.5842)
					(thickness 0.1524)
				)
				(justify left)
			)
		)
		(property "Value" ""
			(at 0 0 90)
			(layer "F.Fab")
			(effects
				(font
					(size 1.27 1.27)
				)
			)
		)
		(duplicate_pad_numbers_are_jumpers no)
		(fp_line
			(start 0.7874 -0.4064)
			(end 0.7874 0.4064)
			(stroke
				(width 0.1524)
				(type default)
			)
			(layer "F.SilkS")
		)
		(fp_line
			(start -0.7874 -0.4064)
			(end 0.7874 -0.4064)
			(stroke
				(width 0.1524)
				(type default)
			)
			(layer "F.SilkS")
		)
		(fp_line
			(start 0 0.381)
			(end 0 -0.381)
			(stroke
				(width 0.1524)
				(type default)
			)
			(layer "F.SilkS")
		)
		(fp_line
			(start 0.7874 0.4064)
			(end -0.7874 0.4064)
			(stroke
				(width 0.1524)
				(type default)
			)
			(layer "F.SilkS")
		)
		(fp_line
			(start -0.7874 0.4064)
			(end -0.7874 -0.4064)
			(stroke
				(width 0.1524)
				(type default)
			)
			(layer "F.SilkS")
		)
		(fp_poly
			(pts
				(xy -0.5334 0.254) (xy -0.635 0.254) (xy -0.635 0.2286) (xy -0.635 -0.254) (xy -0.5334 -0.254) (xy -0.5334 -0.2794)
				(xy 0.5334 -0.2794) (xy 0.5334 -0.254) (xy 0.635 -0.254) (xy 0.635 0.254) (xy 0.5334 0.254) (xy 0.5334 0.2794)
				(xy -0.508 0.2794) (xy -0.5334 0.2794)
			)
			(stroke
				(width 0)
				(type default)
			)
			(fill no)
			(layer "F.CrtYd")
		)
		(pad "1" smd rect
			(at 0.40005 0 90)
			(size 0.4572 0.508)
			(layers "F.Cu" "F.Mask" "F.Paste")
			(net "P12V")
		)
		(pad "2" smd rect
			(at -0.40005 0 90)
			(size 0.4572 0.508)
			(layers "F.Cu" "F.Mask" "F.Paste")
			(net "GND")
		)
	)
	(footprint ""
		(layer "F.Cu")
		(at 40.303958 -370.099336 180)
		(property "Reference" "R24"
			(at -1.863598 -0.010922 0)
			(unlocked yes)
			(layer "F.SilkS")
			(effects
				(font
					(size 0.7874 0.5842)
					(thickness 0.1524)
				)
				(justify left)
			)
		)
		(property "Value" ""
			(at 0 0 180)
			(layer "F.Fab")
			(effects
				(font
					(size 1.27 1.27)
				)
			)
		)
		(duplicate_pad_numbers_are_jumpers no)
		(fp_line
			(start 0.7874 0.4064)
			(end -0.7874 0.4064)
			(stroke
				(width 0.1524)
				(type default)
			)
			(layer "F.SilkS")
		)
		(fp_line
			(start 0.7874 -0.4064)
			(end 0.7874 0.4064)
			(stroke
				(width 0.1524)
				(type default)
			)
			(layer "F.SilkS")
		)
		(fp_line
			(start -0.7874 0.4064)
			(end -0.7874 -0.4064)
			(stroke
				(width 0.1524)
				(type default)
			)
			(layer "F.SilkS")
		)
		(fp_line
			(start -0.7874 -0.4064)
			(end 0.7874 -0.4064)
			(stroke
				(width 0.1524)
				(type default)
			)
			(layer "F.SilkS")
		)
		(fp_poly
			(pts
				(xy -0.508 0.2794) (xy -0.508 0.2286) (xy -0.635 0.2286) (xy -0.635 -0.254) (xy -0.5334 -0.254)
				(xy -0.5334 -0.2794) (xy 0.5334 -0.2794) (xy 0.5334 -0.254) (xy 0.635 -0.254) (xy 0.635 0.254) (xy 0.5334 0.254)
				(xy 0.5334 0.2794)
			)
			(stroke
				(width 0)
				(type default)
			)
			(fill no)
			(layer "F.CrtYd")
		)
		(pad "1" smd rect
			(at 0.40005 0 180)
			(size 0.4572 0.508)
			(layers "F.Cu" "F.Mask" "F.Paste")
			(net "PSU5_RETURN")
		)
		(pad "2" smd rect
			(at -0.40005 0 180)
			(size 0.4572 0.508)
			(layers "F.Cu" "F.Mask" "F.Paste")
			(net "GND")
		)
	)
)
